# S9S_MB_2U (Grand Teton) — schematic netlist excerpt (pin names and nets, part order shuffled) for the footprints in the layout excerpt that follows; sources: Cadence DE-HDL packaged netlist, KiCad conversion of 03242023_DA0F0TMBIJ0_F0T_Motherboard_J_brd_V01_OCP.brd

PC2234  Q_CAP  1UF 25V 10% EMPTY  pkg C0402  page 242 : A = GND ; B = P12V_SCM_REG
C2272  Q_CAP  1000PF 50V 5% EMPTY  pkg 0402  page 145 : A = GPU_3V3IO_RSVD4_ISO ; B = GND

(kicad_pcb
	(version 20260206)
	(generator "pcbnew")
	(generator_version "10.0")
	(general
		(thickness 1.6)
		(legacy_teardrops no)
	)
	(paper "A4")
	(title_block
		(title "03242023_DA0F0TMBIJ0_F0T_Motherboard_J_brd_V01_OCP.brd")
		(comment 1 "Grand Teton / footprints 2276-2277 of 6105")
	)
	(layers
		(0 "F.Cu" signal "TOP")
		(4 "In1.Cu" signal "GND")
		(6 "In2.Cu" signal "IN1")
		(8 "In3.Cu" signal "GND1")
		(10 "In4.Cu" signal "IN2")
		(12 "In5.Cu" signal "GND2")
		(14 "In6.Cu" signal "IN3")
		(16 "In7.Cu" signal "GND3")
		(18 "In8.Cu" signal "VCC")
		(20 "In9.Cu" signal "VCC1")
		(22 "In10.Cu" signal "GND4")
		(24 "In11.Cu" signal "IN4")
		(26 "In12.Cu" signal "GND5")
		(28 "In13.Cu" signal "IN5")
		(30 "In14.Cu" signal "GND6")
		(32 "In15.Cu" signal "IN6")
		(34 "In16.Cu" signal "GND7")
		(2 "B.Cu" signal "BOTTOM")
		(9 "F.Adhes" user "F.Adhesive")
		(11 "B.Adhes" user "B.Adhesive")
		(13 "F.Paste" user "Package Geometry/Pastemask Top")
		(15 "B.Paste" user "Package Geometry/Pastemask Bottom")
		(5 "F.SilkS" user "Ref Des/Silkscreen Top")
		(7 "B.SilkS" user "Ref Des/Silkscreen Bottom")
		(1 "F.Mask" user "Board Geometry/Soldermask Top")
		(3 "B.Mask" user "Board Geometry/Soldermask Bottom")
		(17 "Dwgs.User" user "User.Drawings")
		(19 "Cmts.User" user "User.Comments")
		(21 "Eco1.User" user "User.Eco1")
		(23 "Eco2.User" user "User.Eco2")
		(25 "Edge.Cuts" user "Board Geometry/Outline")
		(27 "Margin" user)
		(31 "F.CrtYd" user "Package Geometry/Place Bound Top")
		(29 "B.CrtYd" user "Package Geometry/Place Bound Bottom")
		(35 "F.Fab" user "Ref Des/Assembly Top")
		(33 "B.Fab" user "Ref Des/Assembly Bottom")
	)
	(footprint ""
		(layer "F.Cu")
		(at 185.806842 -24.170132)
		(property "Reference" "PC2234"
			(at 0 0 0)
			(layer "F.SilkS")
			(hide yes)
			(effects
				(font
					(size 1.27 1.27)
				)
			)
		)
		(property "Value" ""
			(at 0 0 0)
			(layer "F.Fab")
			(effects
				(font
					(size 1.27 1.27)
				)
			)
		)
		(duplicate_pad_numbers_are_jumpers no)
		(fp_line
			(start -0.7874 -0.4064)
			(end 0.7874 -0.4064)
			(stroke
				(width 0.1524)
				(type default)
			)
			(layer "F.SilkS")
		)
		(fp_line
			(start -0.7874 0.4064)
			(end -0.7874 -0.4064)
			(stroke
				(width 0.1524)
				(type default)
			)
			(layer "F.SilkS")
		)
		(fp_line
			(start 0.7874 -0.4064)
			(end 0.7874 0.4064)
			(stroke
				(width 0.1524)
				(type default)
			)
			(layer "F.SilkS")
		)
		(fp_line
			(start 0.7874 0.4064)
			(end -0.7874 0.4064)
			(stroke
				(width 0.1524)
				(type default)
			)
			(layer "F.SilkS")
		)
		(fp_line
			(start -0.67945 -0.305054)
			(end -0.12065 -0.305054)
			(stroke
				(width 0.1)
				(type default)
			)
			(layer "F.Fab")
		)
		(fp_line
			(start -0.67945 0.3048)
			(end -0.67945 -0.305054)
			(stroke
				(width 0.1)
				(type default)
			)
			(layer "F.Fab")
		)
		(fp_line
			(start -0.12065 -0.305054)
			(end -0.12065 -0.2794)
			(stroke
				(width 0.1)
				(type default)
			)
			(layer "F.Fab")
		)
		(fp_line
			(start -0.12065 -0.2794)
			(end 0.12065 -0.2794)
			(stroke
				(width 0.1)
				(type default)
			)
			(layer "F.Fab")
		)
		(fp_line
			(start -0.12065 0.2794)
			(end -0.12065 0.3048)
			(stroke
				(width 0.1)
				(type default)
			)
			(layer "F.Fab")
		)
		(fp_line
			(start -0.12065 0.3048)
			(end -0.67945 0.3048)
			(stroke
				(width 0.1)
				(type default)
			)
			(layer "F.Fab")
		)
		(fp_line
			(start 0.120396 0.2794)
			(end -0.12065 0.2794)
			(stroke
				(width 0.1)
				(type default)
			)
			(layer "F.Fab")
		)
		(fp_line
			(start 0.120396 0.3048)
			(end 0.120396 0.2794)
			(stroke
				(width 0.1)
				(type default)
			)
			(layer "F.Fab")
		)
		(fp_line
			(start 0.12065 -0.3048)
			(end 0.67945 -0.3048)
			(stroke
				(width 0.1)
				(type default)
			)
			(layer "F.Fab")
		)
		(fp_line
			(start 0.12065 -0.2794)
			(end 0.12065 -0.3048)
			(stroke
				(width 0.1)
				(type default)
			)
			(layer "F.Fab")
		)
		(fp_line
			(start 0.67945 -0.3048)
			(end 0.67945 0.3048)
			(stroke
				(width 0.1)
				(type default)
			)
			(layer "F.Fab")
		)
		(fp_line
			(start 0.67945 0.3048)
			(end 0.120396 0.3048)
			(stroke
				(width 0.1)
				(type default)
			)
			(layer "F.Fab")
		)
		(pad "1" smd circle
			(at -0.40005 0)
			(size 0 0)
			(layers "F.Cu" "F.Mask" "F.Paste")
			(net "GND")
		)
		(pad "2" smd circle
			(at 0.40005 0)
			(size 0 0)
			(layers "F.Cu" "F.Mask" "F.Paste")
			(net "P12V_SCM_REG")
		)
	)
	(footprint ""
		(layer "F.Cu")
		(at 357.587042 -392.04265 180)
		(property "Reference" "C2272"
			(at 0 0 180)
			(layer "F.SilkS")
			(hide yes)
			(effects
				(font
					(size 1.27 1.27)
				)
			)
		)
		(property "Value" ""
			(at 0 0 180)
			(layer "F.Fab")
			(effects
				(font
					(size 1.27 1.27)
				)
			)
		)
		(duplicate_pad_numbers_are_jumpers no)
		(fp_line
			(start 0.7874 0.4064)
			(end -0.7874 0.4064)
			(stroke
				(width 0.1524)
				(type default)
			)
			(layer "F.SilkS")
		)
		(fp_line
			(start 0.7874 -0.4064)
			(end 0.7874 0.4064)
			(stroke
				(width 0.1524)
				(type default)
			)
			(layer "F.SilkS")
		)
		(fp_line
			(start -0.7874 0.4064)
			(end -0.7874 -0.4064)
			(stroke
				(width 0.1524)
				(type default)
			)
			(layer "F.SilkS")
		)
		(fp_line
			(start -0.7874 -0.4064)
			(end 0.7874 -0.4064)
			(stroke
				(width 0.1524)
				(type default)
			)
			(layer "F.SilkS")
		)
		(fp_line
			(start 0.67945 0.3048)
			(end 0.120396 0.3048)
			(stroke
				(width 0.1)
				(type default)
			)
			(layer "F.Fab")
		)
		(fp_line
			(start 0.67945 -0.3048)
			(end 0.67945 0.3048)
			(stroke
				(width 0.1)
				(type default)
			)
			(layer "F.Fab")
		)
		(fp_line
			(start 0.12065 -0.2794)
			(end 0.12065 -0.3048)
			(stroke
				(width 0.1)
				(type default)
			)
			(layer "F.Fab")
		)
		(fp_line
			(start 0.12065 -0.3048)
			(end 0.67945 -0.3048)
			(stroke
				(width 0.1)
				(type default)
			)
			(layer "F.Fab")
		)
		(fp_line
			(start 0.120396 0.3048)
			(end 0.120396 0.2794)
			(stroke
				(width 0.1)
				(type default)
			)
			(layer "F.Fab")
		)
		(fp_line
			(start 0.120396 0.2794)
			(end -0.12065 0.2794)
			(stroke
				(width 0.1)
				(type default)
			)
			(layer "F.Fab")
		)
		(fp_line
			(start -0.12065 0.3048)
			(end -0.67945 0.3048)
			(stroke
				(width 0.1)
				(type default)
			)
			(layer "F.Fab")
		)
		(fp_line
			(start -0.12065 0.2794)
			(end -0.12065 0.3048)
			(stroke
				(width 0.1)
				(type default)
			)
			(layer "F.Fab")
		)
		(fp_line
			(start -0.12065 -0.2794)
			(end 0.12065 -0.2794)
			(stroke
				(width 0.1)
				(type default)
			)
			(layer "F.Fab")
		)
		(fp_line
			(start -0.12065 -0.305054)
			(end -0.12065 -0.2794)
			(stroke
				(width 0.1)
				(type default)
			)
			(layer "F.Fab")
		)
		(fp_line
			(start -0.67945 0.3048)
			(end -0.67945 -0.305054)
			(stroke
				(width 0.1)
				(type default)
			)
			(layer "F.Fab")
		)
		(fp_line
			(start -0.67945 -0.305054)
			(end -0.12065 -0.305054)
			(stroke
				(width 0.1)
				(type default)
			)
			(layer "F.Fab")
		)
		(pad "1" smd circle
			(at -0.40005 0 180)
			(size 0 0)
			(layers "F.Cu" "F.Mask" "F.Paste")
			(net "GPU_3V3IO_RSVD4_ISO")
		)
		(pad "2" smd circle
			(at 0.40005 0 180)
			(size 0 0)
			(layers "F.Cu" "F.Mask" "F.Paste")
			(net "GND")
		)
	)
)
